(kicad_pcb
	(version 20260206)
	(generator "pcbnew")
	(generator_version "10.0")
	(general
		(thickness 1.6)
		(legacy_teardrops no)
	)
	(paper "A4")
	(title_block
		(title "01162023_DA0F0TEBIF0_F0T_Expander_BD_F_brd_V02_OCP.brd")
		(comment 1 "Grand Teton / footprints 2983-2988 of 9728")
	)
	(layers
		(0 "F.Cu" signal "TOP")
		(4 "In1.Cu" signal "GND")
		(6 "In2.Cu" signal "VCC")
		(8 "In3.Cu" signal "VCC1")
		(10 "In4.Cu" signal "GND1")
		(12 "In5.Cu" signal "IN1")
		(14 "In6.Cu" signal "GND2")
		(16 "In7.Cu" signal "IN2")
		(18 "In8.Cu" signal "GND3")
		(20 "In9.Cu" signal "IN3")
		(22 "In10.Cu" signal "GND4")
		(24 "In11.Cu" signal "IN4")
		(26 "In12.Cu" signal "GND5")
		(28 "In13.Cu" signal "IN5")
		(30 "In14.Cu" signal "GND6")
		(32 "In15.Cu" signal "IN6")
		(34 "In16.Cu" signal "GND7")
		(2 "B.Cu" signal "BOTTOM")
		(9 "F.Adhes" user "F.Adhesive")
		(11 "B.Adhes" user "B.Adhesive")
		(13 "F.Paste" user "Package Geometry/Pastemask Top")
		(15 "B.Paste" user "Package Geometry/Pastemask Bottom")
		(5 "F.SilkS" user "Ref Des/Silkscreen Top")
		(7 "B.SilkS" user "Ref Des/Silkscreen Bottom")
		(1 "F.Mask" user "Board Geometry/Soldermask Top")
		(3 "B.Mask" user "Board Geometry/Soldermask Bottom")
		(17 "Dwgs.User" user "User.Drawings")
		(19 "Cmts.User" user "User.Comments")
		(21 "Eco1.User" user "User.Eco1")
		(23 "Eco2.User" user "User.Eco2")
		(25 "Edge.Cuts" user "Board Geometry/Outline")
		(27 "Margin" user)
		(31 "F.CrtYd" user "Package Geometry/Place Bound Top")
		(29 "B.CrtYd" user "Package Geometry/Place Bound Bottom")
		(35 "F.Fab" user "Ref Des/Assembly Top")
		(33 "B.Fab" user "Ref Des/Assembly Bottom")
	)
	(footprint ""
		(layer "F.Cu")
		(at 130.25882 -319.420494 90)
		(property "Reference" "R5790"
			(at 0 0 90)
			(layer "F.SilkS")
			(hide yes)
			(effects
				(font
					(size 1.27 1.27)
				)
			)
		)
		(property "Value" ""
			(at 0 0 90)
			(layer "F.Fab")
			(effects
				(font
					(size 1.27 1.27)
				)
			)
		)
		(duplicate_pad_numbers_are_jumpers no)
		(fp_line
			(start 2.576322 -1.1303)
			(end 2.576322 1.1303)
			(stroke
				(width 0.1524)
				(type default)
			)
			(layer "F.SilkS")
		)
		(fp_line
			(start -2.576322 -1.1303)
			(end 2.576322 -1.1303)
			(stroke
				(width 0.1524)
				(type default)
			)
			(layer "F.SilkS")
		)
		(fp_line
			(start 2.576322 1.1303)
			(end -2.576322 1.1303)
			(stroke
				(width 0.1524)
				(type default)
			)
			(layer "F.SilkS")
		)
		(fp_line
			(start -2.576322 1.1303)
			(end -2.576322 -1.1303)
			(stroke
				(width 0.1524)
				(type default)
			)
			(layer "F.SilkS")
		)
		(fp_line
			(start 1.649984 -0.899922)
			(end -1.649984 -0.899922)
			(stroke
				(width 0.1)
				(type default)
			)
			(layer "F.Fab")
		)
		(fp_line
			(start -1.649984 -0.899922)
			(end -1.649984 0.899922)
			(stroke
				(width 0.1)
				(type default)
			)
			(layer "F.Fab")
		)
		(fp_line
			(start 1.649984 0.899922)
			(end 1.649984 -0.899922)
			(stroke
				(width 0.1)
				(type default)
			)
			(layer "F.Fab")
		)
		(fp_line
			(start -1.649984 0.899922)
			(end 1.649984 0.899922)
			(stroke
				(width 0.1)
				(type default)
			)
			(layer "F.Fab")
		)
		(pad "1A" smd rect
			(at -1.700022 0 90)
			(size 1.4986 2.0066)
			(layers "F.Cu" "F.Mask" "F.Paste")
			(net "P0V8_PEX1")
		)
		(pad "1B" smd rect
			(at -1.077722 0 90)
			(size 0.254 0.508)
			(layers "F.Cu" "F.Mask" "F.Paste")
			(net "P0V8_PEX1")
		)
		(pad "2A" smd rect
			(at 1.700022 0 90)
			(size 1.4986 2.0066)
			(layers "F.Cu" "F.Mask" "F.Paste")
			(net "P0V8_SERDES_VDDA_PEX1")
		)
		(pad "2B" smd rect
			(at 1.077722 0 90)
			(size 0.254 0.508)
			(layers "F.Cu" "F.Mask" "F.Paste")
			(net "P0V8_SERDES_VDDA_PEX1")
		)
	)
	(footprint ""
		(layer "F.Cu")
		(at 314.573666 -27.006296 -90)
		(property "Reference" "PC956"
			(at 0 0 270)
			(layer "F.SilkS")
			(hide yes)
			(effects
				(font
					(size 1.27 1.27)
				)
			)
		)
		(property "Value" ""
			(at 0 0 270)
			(layer "F.Fab")
			(effects
				(font
					(size 1.27 1.27)
				)
			)
		)
		(duplicate_pad_numbers_are_jumpers no)
		(fp_line
			(start -0.7874 0.4064)
			(end -0.7874 -0.4064)
			(stroke
				(width 0.1524)
				(type default)
			)
			(layer "F.SilkS")
		)
		(fp_line
			(start 0.7874 0.4064)
			(end -0.7874 0.4064)
			(stroke
				(width 0.1524)
				(type default)
			)
			(layer "F.SilkS")
		)
		(fp_line
			(start -0.7874 -0.4064)
			(end 0.7874 -0.4064)
			(stroke
				(width 0.1524)
				(type default)
			)
			(layer "F.SilkS")
		)
		(fp_line
			(start 0.7874 -0.4064)
			(end 0.7874 0.4064)
			(stroke
				(width 0.1524)
				(type default)
			)
			(layer "F.SilkS")
		)
		(fp_line
			(start -0.67945 0.3048)
			(end -0.67945 -0.305054)
			(stroke
				(width 0.1)
				(type default)
			)
			(layer "F.Fab")
		)
		(fp_line
			(start -0.12065 0.3048)
			(end -0.67945 0.3048)
			(stroke
				(width 0.1)
				(type default)
			)
			(layer "F.Fab")
		)
		(fp_line
			(start 0.120396 0.3048)
			(end 0.120396 0.2794)
			(stroke
				(width 0.1)
				(type default)
			)
			(layer "F.Fab")
		)
		(fp_line
			(start 0.67945 0.3048)
			(end 0.120396 0.3048)
			(stroke
				(width 0.1)
				(type default)
			)
			(layer "F.Fab")
		)
		(fp_line
			(start -0.12065 0.2794)
			(end -0.12065 0.3048)
			(stroke
				(width 0.1)
				(type default)
			)
			(layer "F.Fab")
		)
		(fp_line
			(start 0.120396 0.2794)
			(end -0.12065 0.2794)
			(stroke
				(width 0.1)
				(type default)
			)
			(layer "F.Fab")
		)
		(fp_line
			(start -0.12065 -0.2794)
			(end 0.12065 -0.2794)
			(stroke
				(width 0.1)
				(type default)
			)
			(layer "F.Fab")
		)
		(fp_line
			(start 0.12065 -0.2794)
			(end 0.12065 -0.3048)
			(stroke
				(width 0.1)
				(type default)
			)
			(layer "F.Fab")
		)
		(fp_line
			(start 0.12065 -0.3048)
			(end 0.67945 -0.3048)
			(stroke
				(width 0.1)
				(type default)
			)
			(layer "F.Fab")
		)
		(fp_line
			(start 0.67945 -0.3048)
			(end 0.67945 0.3048)
			(stroke
				(width 0.1)
				(type default)
			)
			(layer "F.Fab")
		)
		(fp_line
			(start -0.67945 -0.305054)
			(end -0.12065 -0.305054)
			(stroke
				(width 0.1)
				(type default)
			)
			(layer "F.Fab")
		)
		(fp_line
			(start -0.12065 -0.305054)
			(end -0.12065 -0.2794)
			(stroke
				(width 0.1)
				(type default)
			)
			(layer "F.Fab")
		)
		(pad "1" smd circle
			(at -0.40005 0 270)
			(size 0 0)
			(layers "F.Cu" "F.Mask" "F.Paste")
			(net "P3V3_SSD11_CO_MODE")
		)
		(pad "2" smd circle
			(at 0.40005 0 270)
			(size 0 0)
			(layers "F.Cu" "F.Mask" "F.Paste")
			(net "GND")
		)
	)
	(footprint ""
		(layer "F.Cu")
		(at 377.722384 -250.070874 -90)
		(property "Reference" "R1408"
			(at 0 0 270)
			(layer "F.SilkS")
			(hide yes)
			(effects
				(font
					(size 1.27 1.27)
				)
			)
		)
		(property "Value" ""
			(at 0 0 270)
			(layer "F.Fab")
			(effects
				(font
					(size 1.27 1.27)
				)
			)
		)
		(duplicate_pad_numbers_are_jumpers no)
		(fp_line
			(start -0.7874 0.4064)
			(end -0.7874 -0.4064)
			(stroke
				(width 0.1524)
				(type default)
			)
			(layer "F.SilkS")
		)
		(fp_line
			(start 0.7874 0.4064)
			(end -0.7874 0.4064)
			(stroke
				(width 0.1524)
				(type default)
			)
			(layer "F.SilkS")
		)
		(fp_line
			(start -0.7874 -0.4064)
			(end 0.7874 -0.4064)
			(stroke
				(width 0.1524)
				(type default)
			)
			(layer "F.SilkS")
		)
		(fp_line
			(start 0.7874 -0.4064)
			(end 0.7874 0.4064)
			(stroke
				(width 0.1524)
				(type default)
			)
			(layer "F.SilkS")
		)
		(fp_line
			(start -0.67945 0.3048)
			(end -0.67945 -0.305054)
			(stroke
				(width 0.1)
				(type default)
			)
			(layer "F.Fab")
		)
		(fp_line
			(start -0.12065 0.3048)
			(end -0.67945 0.3048)
			(stroke
				(width 0.1)
				(type default)
			)
			(layer "F.Fab")
		)
		(fp_line
			(start 0.120396 0.3048)
			(end 0.120396 0.2794)
			(stroke
				(width 0.1)
				(type default)
			)
			(layer "F.Fab")
		)
		(fp_line
			(start 0.67945 0.3048)
			(end 0.120396 0.3048)
			(stroke
				(width 0.1)
				(type default)
			)
			(layer "F.Fab")
		)
		(fp_line
			(start -0.12065 0.2794)
			(end -0.12065 0.3048)
			(stroke
				(width 0.1)
				(type default)
			)
			(layer "F.Fab")
		)
		(fp_line
			(start 0.120396 0.2794)
			(end -0.12065 0.2794)
			(stroke
				(width 0.1)
				(type default)
			)
			(layer "F.Fab")
		)
		(fp_line
			(start -0.12065 -0.2794)
			(end 0.12065 -0.2794)
			(stroke
				(width 0.1)
				(type default)
			)
			(layer "F.Fab")
		)
		(fp_line
			(start 0.12065 -0.2794)
			(end 0.12065 -0.3048)
			(stroke
				(width 0.1)
				(type default)
			)
			(layer "F.Fab")
		)
		(fp_line
			(start 0.12065 -0.3048)
			(end 0.67945 -0.3048)
			(stroke
				(width 0.1)
				(type default)
			)
			(layer "F.Fab")
		)
		(fp_line
			(start 0.67945 -0.3048)
			(end 0.67945 0.3048)
			(stroke
				(width 0.1)
				(type default)
			)
			(layer "F.Fab")
		)
		(fp_line
			(start -0.67945 -0.305054)
			(end -0.12065 -0.305054)
			(stroke
				(width 0.1)
				(type default)
			)
			(layer "F.Fab")
		)
		(fp_line
			(start -0.12065 -0.305054)
			(end -0.12065 -0.2794)
			(stroke
				(width 0.1)
				(type default)
			)
			(layer "F.Fab")
		)
		(pad "1" smd circle
			(at -0.40005 0 270)
			(size 0 0)
			(layers "F.Cu" "F.Mask" "F.Paste")
			(net "PEX3_MODE_SEL3")
		)
		(pad "2" smd circle
			(at 0.40005 0 270)
			(size 0 0)
			(layers "F.Cu" "F.Mask" "F.Paste")
			(net "P1V8_PEX")
		)
	)
	(footprint ""
		(layer "F.Cu")
		(at 21.513546 -254.753364 -90)
		(property "Reference" "R6153"
			(at 0 0 270)
			(layer "F.SilkS")
			(hide yes)
			(effects
				(font
					(size 1.27 1.27)
				)
			)
		)
		(property "Value" ""
			(at 0 0 270)
			(layer "F.Fab")
			(effects
				(font
					(size 1.27 1.27)
				)
			)
		)
		(duplicate_pad_numbers_are_jumpers no)
		(fp_line
			(start -0.7874 0.4064)
			(end -0.7874 -0.4064)
			(stroke
				(width 0.1524)
				(type default)
			)
			(layer "F.SilkS")
		)
		(fp_line
			(start 0.7874 0.4064)
			(end -0.7874 0.4064)
			(stroke
				(width 0.1524)
				(type default)
			)
			(layer "F.SilkS")
		)
		(fp_line
			(start -0.7874 -0.4064)
			(end 0.7874 -0.4064)
			(stroke
				(width 0.1524)
				(type default)
			)
			(layer "F.SilkS")
		)
		(fp_line
			(start 0.7874 -0.4064)
			(end 0.7874 0.4064)
			(stroke
				(width 0.1524)
				(type default)
			)
			(layer "F.SilkS")
		)
		(fp_line
			(start -0.67945 0.3048)
			(end -0.67945 -0.305054)
			(stroke
				(width 0.1)
				(type default)
			)
			(layer "F.Fab")
		)
		(fp_line
			(start -0.12065 0.3048)
			(end -0.67945 0.3048)
			(stroke
				(width 0.1)
				(type default)
			)
			(layer "F.Fab")
		)
		(fp_line
			(start 0.120396 0.3048)
			(end 0.120396 0.2794)
			(stroke
				(width 0.1)
				(type default)
			)
			(layer "F.Fab")
		)
		(fp_line
			(start 0.67945 0.3048)
			(end 0.120396 0.3048)
			(stroke
				(width 0.1)
				(type default)
			)
			(layer "F.Fab")
		)
		(fp_line
			(start -0.12065 0.2794)
			(end -0.12065 0.3048)
			(stroke
				(width 0.1)
				(type default)
			)
			(layer "F.Fab")
		)
		(fp_line
			(start 0.120396 0.2794)
			(end -0.12065 0.2794)
			(stroke
				(width 0.1)
				(type default)
			)
			(layer "F.Fab")
		)
		(fp_line
			(start -0.12065 -0.2794)
			(end 0.12065 -0.2794)
			(stroke
				(width 0.1)
				(type default)
			)
			(layer "F.Fab")
		)
		(fp_line
			(start 0.12065 -0.2794)
			(end 0.12065 -0.3048)
			(stroke
				(width 0.1)
				(type default)
			)
			(layer "F.Fab")
		)
		(fp_line
			(start 0.12065 -0.3048)
			(end 0.67945 -0.3048)
			(stroke
				(width 0.1)
				(type default)
			)
			(layer "F.Fab")
		)
		(fp_line
			(start 0.67945 -0.3048)
			(end 0.67945 0.3048)
			(stroke
				(width 0.1)
				(type default)
			)
			(layer "F.Fab")
		)
		(fp_line
			(start -0.67945 -0.305054)
			(end -0.12065 -0.305054)
			(stroke
				(width 0.1)
				(type default)
			)
			(layer "F.Fab")
		)
		(fp_line
			(start -0.12065 -0.305054)
			(end -0.12065 -0.2794)
			(stroke
				(width 0.1)
				(type default)
			)
			(layer "F.Fab")
		)
		(pad "1" smd circle
			(at -0.40005 0 270)
			(size 0 0)
			(layers "F.Cu" "F.Mask" "F.Paste")
			(net "PEX0_SYS_ERR_R_N")
		)
		(pad "2" smd circle
			(at 0.40005 0 270)
			(size 0 0)
			(layers "F.Cu" "F.Mask" "F.Paste")
			(net "P1V8_PEX")
		)
	)
	(footprint ""
		(layer "F.Cu")
		(at 333.020416 -70.307454 90)
		(property "Reference" "PC858"
			(at 0 0 90)
			(layer "F.SilkS")
			(hide yes)
			(effects
				(font
					(size 1.27 1.27)
				)
			)
		)
		(property "Value" ""
			(at 0 0 90)
			(layer "F.Fab")
			(effects
				(font
					(size 1.27 1.27)
				)
			)
		)
		(duplicate_pad_numbers_are_jumpers no)
		(fp_line
			(start 0.7874 -0.4064)
			(end 0.7874 0.4064)
			(stroke
				(width 0.1524)
				(type default)
			)
			(layer "F.SilkS")
		)
		(fp_line
			(start -0.7874 -0.4064)
			(end 0.7874 -0.4064)
			(stroke
				(width 0.1524)
				(type default)
			)
			(layer "F.SilkS")
		)
		(fp_line
			(start 0.7874 0.4064)
			(end -0.7874 0.4064)
			(stroke
				(width 0.1524)
				(type default)
			)
			(layer "F.SilkS")
		)
		(fp_line
			(start -0.7874 0.4064)
			(end -0.7874 -0.4064)
			(stroke
				(width 0.1524)
				(type default)
			)
			(layer "F.SilkS")
		)
		(fp_line
			(start -0.12065 -0.305054)
			(end -0.12065 -0.2794)
			(stroke
				(width 0.1)
				(type default)
			)
			(layer "F.Fab")
		)
		(fp_line
			(start -0.67945 -0.305054)
			(end -0.12065 -0.305054)
			(stroke
				(width 0.1)
				(type default)
			)
			(layer "F.Fab")
		)
		(fp_line
			(start 0.67945 -0.3048)
			(end 0.67945 0.3048)
			(stroke
				(width 0.1)
				(type default)
			)
			(layer "F.Fab")
		)
		(fp_line
			(start 0.12065 -0.3048)
			(end 0.67945 -0.3048)
			(stroke
				(width 0.1)
				(type default)
			)
			(layer "F.Fab")
		)
		(fp_line
			(start 0.12065 -0.2794)
			(end 0.12065 -0.3048)
			(stroke
				(width 0.1)
				(type default)
			)
			(layer "F.Fab")
		)
		(fp_line
			(start -0.12065 -0.2794)
			(end 0.12065 -0.2794)
			(stroke
				(width 0.1)
				(type default)
			)
			(layer "F.Fab")
		)
		(fp_line
			(start 0.120396 0.2794)
			(end -0.12065 0.2794)
			(stroke
				(width 0.1)
				(type default)
			)
			(layer "F.Fab")
		)
		(fp_line
			(start -0.12065 0.2794)
			(end -0.12065 0.3048)
			(stroke
				(width 0.1)
				(type default)
			)
			(layer "F.Fab")
		)
		(fp_line
			(start 0.67945 0.3048)
			(end 0.120396 0.3048)
			(stroke
				(width 0.1)
				(type default)
			)
			(layer "F.Fab")
		)
		(fp_line
			(start 0.120396 0.3048)
			(end 0.120396 0.2794)
			(stroke
				(width 0.1)
				(type default)
			)
			(layer "F.Fab")
		)
		(fp_line
			(start -0.12065 0.3048)
			(end -0.67945 0.3048)
			(stroke
				(width 0.1)
				(type default)
			)
			(layer "F.Fab")
		)
		(fp_line
			(start -0.67945 0.3048)
			(end -0.67945 -0.305054)
			(stroke
				(width 0.1)
				(type default)
			)
			(layer "F.Fab")
		)
		(pad "1" smd circle
			(at -0.40005 0 90)
			(size 0 0)
			(layers "F.Cu" "F.Mask" "F.Paste")
			(net "P12V_AUX")
		)
		(pad "2" smd circle
			(at 0.40005 0 90)
			(size 0 0)
			(layers "F.Cu" "F.Mask" "F.Paste")
			(net "GND")
		)
	)
	(footprint ""
		(layer "F.Cu")
		(at 104.243632 -43.85691)
		(property "Reference" "R542"
			(at 0 0 0)
			(layer "F.SilkS")
			(hide yes)
			(effects
				(font
					(size 1.27 1.27)
				)
			)
		)
		(property "Value" ""
			(at 0 0 0)
			(layer "F.Fab")
			(effects
				(font
					(size 1.27 1.27)
				)
			)
		)
		(duplicate_pad_numbers_are_jumpers no)
		(fp_line
			(start -0.7874 -0.4064)
			(end 0.7874 -0.4064)
			(stroke
				(width 0.1524)
				(type default)
			)
			(layer "F.SilkS")
		)
		(fp_line
			(start -0.7874 0.4064)
			(end -0.7874 -0.4064)
			(stroke
				(width 0.1524)
				(type default)
			)
			(layer "F.SilkS")
		)
		(fp_line
			(start 0.7874 -0.4064)
			(end 0.7874 0.4064)
			(stroke
				(width 0.1524)
				(type default)
			)
			(layer "F.SilkS")
		)
		(fp_line
			(start 0.7874 0.4064)
			(end -0.7874 0.4064)
			(stroke
				(width 0.1524)
				(type default)
			)
			(layer "F.SilkS")
		)
		(fp_line
			(start -0.67945 -0.305054)
			(end -0.12065 -0.305054)
			(stroke
				(width 0.1)
				(type default)
			)
			(layer "F.Fab")
		)
		(fp_line
			(start -0.67945 0.3048)
			(end -0.67945 -0.305054)
			(stroke
				(width 0.1)
				(type default)
			)
			(layer "F.Fab")
		)
		(fp_line
			(start -0.12065 -0.305054)
			(end -0.12065 -0.2794)
			(stroke
				(width 0.1)
				(type default)
			)
			(layer "F.Fab")
		)
		(fp_line
			(start -0.12065 -0.2794)
			(end 0.12065 -0.2794)
			(stroke
				(width 0.1)
				(type default)
			)
			(layer "F.Fab")
		)
		(fp_line
			(start -0.12065 0.2794)
			(end -0.12065 0.3048)
			(stroke
				(width 0.1)
				(type default)
			)
			(layer "F.Fab")
		)
		(fp_line
			(start -0.12065 0.3048)
			(end -0.67945 0.3048)
			(stroke
				(width 0.1)
				(type default)
			)
			(layer "F.Fab")
		)
		(fp_line
			(start 0.120396 0.2794)
			(end -0.12065 0.2794)
			(stroke
				(width 0.1)
				(type default)
			)
			(layer "F.Fab")
		)
		(fp_line
			(start 0.120396 0.3048)
			(end 0.120396 0.2794)
			(stroke
				(width 0.1)
				(type default)
			)
			(layer "F.Fab")
		)
		(fp_line
			(start 0.12065 -0.3048)
			(end 0.67945 -0.3048)
			(stroke
				(width 0.1)
				(type default)
			)
			(layer "F.Fab")
		)
		(fp_line
			(start 0.12065 -0.2794)
			(end 0.12065 -0.3048)
			(stroke
				(width 0.1)
				(type default)
			)
			(layer "F.Fab")
		)
		(fp_line
			(start 0.67945 -0.3048)
			(end 0.67945 0.3048)
			(stroke
				(width 0.1)
				(type default)
			)
			(layer "F.Fab")
		)
		(fp_line
			(start 0.67945 0.3048)
			(end 0.120396 0.3048)
			(stroke
				(width 0.1)
				(type default)
			)
			(layer "F.Fab")
		)
		(pad "1" smd circle
			(at -0.40005 0)
			(size 0 0)
			(layers "F.Cu" "F.Mask" "F.Paste")
			(net "SSD3_ADC_A1")
		)
		(pad "2" smd circle
			(at 0.40005 0)
			(size 0 0)
			(layers "F.Cu" "F.Mask" "F.Paste")
			(net "GND")
		)
	)
)
